# T6G (Grand Teton) — schematic netlist excerpt (pin names and nets, part order shuffled) for the footprints in the layout excerpt that follows; sources: Cadence DE-HDL packaged netlist, KiCad conversion of 04192023_DAF0TMB3IC0_F0TG_MB_C_brd_V02_OCP.brd

PC800  Q_CAPP  470UF 2.5V 20% SPCAP  pkg SMLF  page 208 : A = PVDD11_S3_P0 ; B = GND
R918  Q_RES  4.7K 5% EMPTY  pkg 0201LF  page 353 : A = P1V8_CPU1_RT_1D ; B = TEST0_RT_CPU1_P3
PC315_5  Q_CAP  22UF 4V 20% X6S  pkg C0805  page 213 : A = PVDDCR_CPU0_P1 ; B = GND

PQ17  MOSFET_N  BSS138K IC  pkg SMLF  page 193
  DRAIN  = PVDDCR_SOC_P0_EN_GD
  GATE  = PVDDCR_SOC_P0_EN_RC
  SOURCE  = GND

(kicad_pcb
	(version 20260206)
	(generator "pcbnew")
	(generator_version "10.0")
	(general
		(thickness 1.6)
		(legacy_teardrops no)
	)
	(paper "A4")
	(title_block
		(title "04192023_DAF0TMB3IC0_F0TG_MB_C_brd_V02_OCP.brd")
		(comment 1 "Grand Teton / footprints 7751-7754 of 8354")
	)
	(layers
		(0 "F.Cu" signal "TOP")
		(4 "In1.Cu" signal "GND")
		(6 "In2.Cu" signal "IN1")
		(8 "In3.Cu" signal "GND1")
		(10 "In4.Cu" signal "IN2")
		(12 "In5.Cu" signal "GND2")
		(14 "In6.Cu" signal "IN3")
		(16 "In7.Cu" signal "GND3")
		(18 "In8.Cu" signal "VCC")
		(20 "In9.Cu" signal "VCC1")
		(22 "In10.Cu" signal "GND4")
		(24 "In11.Cu" signal "IN4")
		(26 "In12.Cu" signal "GND5")
		(28 "In13.Cu" signal "IN5")
		(30 "In14.Cu" signal "GND6")
		(32 "In15.Cu" signal "IN6")
		(34 "In16.Cu" signal "GND7")
		(2 "B.Cu" signal "BOTTOM")
		(9 "F.Adhes" user "F.Adhesive")
		(11 "B.Adhes" user "B.Adhesive")
		(13 "F.Paste" user "Package Geometry/Pastemask Top")
		(15 "B.Paste" user "Package Geometry/Pastemask Bottom")
		(5 "F.SilkS" user "Ref Des/Silkscreen Top")
		(7 "B.SilkS" user "Ref Des/Silkscreen Bottom")
		(1 "F.Mask" user "Board Geometry/Soldermask Top")
		(3 "B.Mask" user "Board Geometry/Soldermask Bottom")
		(17 "Dwgs.User" user "User.Drawings")
		(19 "Cmts.User" user "User.Comments")
		(21 "Eco1.User" user "User.Eco1")
		(23 "Eco2.User" user "User.Eco2")
		(25 "Edge.Cuts" user "Board Geometry/Outline")
		(27 "Margin" user)
		(31 "F.CrtYd" user "Package Geometry/Place Bound Top")
		(29 "B.CrtYd" user "Package Geometry/Place Bound Bottom")
		(35 "F.Fab" user "Ref Des/Assembly Top")
		(33 "B.Fab" user "Ref Des/Assembly Bottom")
	)
	(footprint ""
		(layer "B.Cu")
		(at 438.903618 -343.656412 -90)
		(property "Reference" "PC800"
			(at 7.654036 -3.431286 270)
			(unlocked yes)
			(layer "B.SilkS")
			(effects
				(font
					(size 0.7874 0.5842)
					(thickness 0.1524)
				)
				(justify left mirror)
			)
		)
		(property "Value" ""
			(at 0 0 90)
			(layer "B.Fab")
			(effects
				(font
					(size 1.27 1.27)
				)
				(justify mirror)
			)
		)
		(duplicate_pad_numbers_are_jumpers no)
		(fp_line
			(start -4.533392 2.249932)
			(end 4.533392 2.249932)
			(stroke
				(width 0.1524)
				(type default)
			)
			(layer "B.SilkS")
		)
		(fp_line
			(start 4.533392 2.249932)
			(end 4.533392 -2.249932)
			(stroke
				(width 0.1524)
				(type default)
			)
			(layer "B.SilkS")
		)
		(fp_line
			(start -4.533392 -2.249932)
			(end -4.533392 2.249932)
			(stroke
				(width 0.1524)
				(type default)
			)
			(layer "B.SilkS")
		)
		(fp_line
			(start 4.533392 -2.249932)
			(end -4.533392 -2.249932)
			(stroke
				(width 0.1524)
				(type default)
			)
			(layer "B.SilkS")
		)
		(fp_rect
			(start 5.39242 2.326132)
			(end 4.533392 -2.326132)
			(stroke
				(width 0)
				(type default)
			)
			(fill yes)
			(layer "B.SilkS")
		)
		(fp_line
			(start -3.750056 2.249932)
			(end 3.750056 2.249932)
			(stroke
				(width 0.1)
				(type default)
			)
			(layer "B.Fab")
		)
		(fp_line
			(start 3.750056 2.249932)
			(end 3.750056 -2.249932)
			(stroke
				(width 0.1)
				(type default)
			)
			(layer "B.Fab")
		)
		(fp_line
			(start -3.750056 -2.249932)
			(end -3.750056 2.249932)
			(stroke
				(width 0.1)
				(type default)
			)
			(layer "B.Fab")
		)
		(fp_line
			(start 3.750056 -2.249932)
			(end -3.750056 -2.249932)
			(stroke
				(width 0.1)
				(type default)
			)
			(layer "B.Fab")
		)
		(fp_text user "+"
			(at 6.322314 0.786384 180)
			(unlocked yes)
			(layer "B.SilkS")
			(effects
				(font
					(size 1.905 1.4224)
					(thickness 0.1524)
				)
				(justify left mirror)
			)
		)
		(fp_text user "-"
			(at -4.618228 0.045466 270)
			(unlocked yes)
			(layer "B.SilkS")
			(effects
				(font
					(size 1.905 1.4224)
					(thickness 0.1524)
				)
				(justify left mirror)
			)
		)
		(fp_text user "+"
			(at 6.322314 0.786384 180)
			(unlocked yes)
			(layer "B.Fab")
			(effects
				(font
					(size 1.905 1.4224)
					(thickness 0.1524)
				)
				(justify left mirror)
			)
		)
		(fp_text user "-"
			(at -4.8514 -0.14605 270)
			(unlocked yes)
			(layer "B.Fab")
			(effects
				(font
					(size 1.905 1.4224)
					(thickness 0.1524)
				)
				(justify left mirror)
			)
		)
		(pad "1" smd rect
			(at 3.199892 0 90)
			(size 2.413 2.8194)
			(layers "B.Cu" "B.Mask" "B.Paste")
			(net "PVDD11_S3_P0")
		)
		(pad "2" smd rect
			(at -3.199892 0 90)
			(size 2.413 2.8194)
			(layers "B.Cu" "B.Mask" "B.Paste")
			(net "GND")
		)
	)
	(footprint ""
		(layer "B.Cu")
		(at 367.595658 -139.780772 -90)
		(property "Reference" "PQ17"
			(at -0.07112 -2.670048 270)
			(unlocked yes)
			(layer "B.SilkS")
			(effects
				(font
					(size 0.7874 0.5842)
					(thickness 0.1524)
				)
				(justify mirror)
			)
		)
		(property "Value" ""
			(at 0 0 90)
			(layer "B.Fab")
			(effects
				(font
					(size 1.27 1.27)
				)
				(justify mirror)
			)
		)
		(duplicate_pad_numbers_are_jumpers no)
		(fp_line
			(start -1.949958 1.610106)
			(end 1.949958 1.610106)
			(stroke
				(width 0.1524)
				(type default)
			)
			(layer "B.SilkS")
		)
		(fp_line
			(start 1.949958 1.610106)
			(end 1.949958 -1.610106)
			(stroke
				(width 0.1524)
				(type default)
			)
			(layer "B.SilkS")
		)
		(fp_line
			(start -1.949958 -1.560068)
			(end -1.949958 1.610106)
			(stroke
				(width 0.1524)
				(type default)
			)
			(layer "B.SilkS")
		)
		(fp_line
			(start 1.949958 -1.610106)
			(end -1.949958 -1.610106)
			(stroke
				(width 0.1524)
				(type default)
			)
			(layer "B.SilkS")
		)
		(fp_line
			(start -0.750062 1.560068)
			(end 0.750062 1.560068)
			(stroke
				(width 0.1)
				(type default)
			)
			(layer "B.Fab")
		)
		(fp_line
			(start 0.750062 1.560068)
			(end 0.750062 -1.560068)
			(stroke
				(width 0.1)
				(type default)
			)
			(layer "B.Fab")
		)
		(fp_line
			(start -0.750062 -1.560068)
			(end -0.750062 1.560068)
			(stroke
				(width 0.1)
				(type default)
			)
			(layer "B.Fab")
		)
		(fp_line
			(start 0.750062 -1.560068)
			(end -0.750062 -1.560068)
			(stroke
				(width 0.1)
				(type default)
			)
			(layer "B.Fab")
		)
		(pad "D" smd rect
			(at -1.100074 0 180)
			(size 1.016 1.4224)
			(layers "B.Cu" "B.Mask" "B.Paste")
			(net "PVDDCR_SOC_P0_EN_GD")
		)
		(pad "G" smd rect
			(at 1.100074 -0.94996 180)
			(size 1.016 1.4224)
			(layers "B.Cu" "B.Mask" "B.Paste")
			(net "PVDDCR_SOC_P0_EN_RC")
		)
		(pad "S" smd rect
			(at 1.100074 0.94996 180)
			(size 1.016 1.4224)
			(layers "B.Cu" "B.Mask" "B.Paste")
			(net "GND")
		)
	)
	(footprint ""
		(layer "B.Cu")
		(at 109.095794 -385.58216 180)
		(property "Reference" "R918"
			(at 0 0 0)
			(layer "B.SilkS")
			(hide yes)
			(effects
				(font
					(size 1.27 1.27)
				)
				(justify mirror)
			)
		)
		(property "Value" ""
			(at 0 0 0)
			(layer "B.Fab")
			(effects
				(font
					(size 1.27 1.27)
				)
				(justify mirror)
			)
		)
		(duplicate_pad_numbers_are_jumpers no)
		(fp_line
			(start 0.32512 0.175006)
			(end 0.32512 -0.175006)
			(stroke
				(width 0.1)
				(type default)
			)
			(layer "B.Fab")
		)
		(fp_line
			(start 0.32512 -0.175006)
			(end -0.32512 -0.175006)
			(stroke
				(width 0.1)
				(type default)
			)
			(layer "B.Fab")
		)
		(fp_line
			(start -0.32512 0.175006)
			(end 0.32512 0.175006)
			(stroke
				(width 0.1)
				(type default)
			)
			(layer "B.Fab")
		)
		(fp_line
			(start -0.32512 -0.175006)
			(end -0.32512 0.175006)
			(stroke
				(width 0.1)
				(type default)
			)
			(layer "B.Fab")
		)
		(pad "1" smd rect
			(at 0.2667 0)
			(size 0.3048 0.381)
			(layers "B.Cu" "B.Mask" "B.Paste")
			(net "P1V8_CPU1_RT_1D")
		)
		(pad "2" smd rect
			(at -0.2667 0 180)
			(size 0.3048 0.381)
			(layers "B.Cu" "B.Mask" "B.Paste")
			(net "TEST0_RT_CPU1_P3")
		)
	)
	(footprint ""
		(layer "B.Cu")
		(at 68.143374 -177.349912 90)
		(property "Reference" "PC315_5"
			(at 0 0 90)
			(layer "B.SilkS")
			(hide yes)
			(effects
				(font
					(size 1.27 1.27)
				)
				(justify mirror)
			)
		)
		(property "Value" ""
			(at 0 0 90)
			(layer "B.Fab")
			(effects
				(font
					(size 1.27 1.27)
				)
				(justify mirror)
			)
		)
		(duplicate_pad_numbers_are_jumpers no)
		(fp_line
			(start 1.524 -0.762)
			(end -1.524 -0.762)
			(stroke
				(width 0.1524)
				(type default)
			)
			(layer "B.SilkS")
		)
		(fp_line
			(start -1.524 -0.762)
			(end -1.524 0.762)
			(stroke
				(width 0.1524)
				(type default)
			)
			(layer "B.SilkS")
		)
		(fp_line
			(start 1.524 0.762)
			(end 1.524 -0.762)
			(stroke
				(width 0.1524)
				(type default)
			)
			(layer "B.SilkS")
		)
		(fp_line
			(start -1.524 0.762)
			(end 1.524 0.762)
			(stroke
				(width 0.1524)
				(type default)
			)
			(layer "B.SilkS")
		)
		(fp_line
			(start 1.1049 -0.724916)
			(end 1.1049 0.724916)
			(stroke
				(width 0.1)
				(type default)
			)
			(layer "B.Fab")
		)
		(fp_line
			(start -1.1049 -0.724916)
			(end 1.1049 -0.724916)
			(stroke
				(width 0.1)
				(type default)
			)
			(layer "B.Fab")
		)
		(fp_line
			(start 1.1049 0.724916)
			(end -1.1049 0.724916)
			(stroke
				(width 0.1)
				(type default)
			)
			(layer "B.Fab")
		)
		(fp_line
			(start -1.1049 0.724916)
			(end -1.1049 -0.724916)
			(stroke
				(width 0.1)
				(type default)
			)
			(layer "B.Fab")
		)
		(pad "1" smd rect
			(at 0.889 0 90)
			(size 1.016 1.27)
			(layers "B.Cu" "B.Mask" "B.Paste")
			(net "PVDDCR_CPU0_P1")
		)
		(pad "2" smd rect
			(at -0.889 0 90)
			(size 1.016 1.27)
			(layers "B.Cu" "B.Mask" "B.Paste")
			(net "GND")
		)
	)
)
